# T6G (Grand Teton) — schematic netlist excerpt (pin names and nets, part order shuffled) for the footprints in the layout excerpt that follows; sources: Cadence DE-HDL packaged netlist, KiCad conversion of 04192023_DAF0TMB3IC0_F0TG_MB_C_brd_V02_OCP.brd

PC151  Q_CAP  2.2UF 10V 10% X6S  pkg C0402  page 196 : A = PVDDCR_CPU0_P0_VCC6 ; B = GND
R3472  Q_RES  0 5% EMPTY  pkg 0402LF  page 126 : A = GND ; B = GPU_WP_HW_CTRL_ISO_N

(kicad_pcb
	(version 20260206)
	(generator "pcbnew")
	(generator_version "10.0")
	(general
		(thickness 1.6)
		(legacy_teardrops no)
	)
	(paper "A4")
	(title_block
		(title "04192023_DAF0TMB3IC0_F0TG_MB_C_brd_V02_OCP.brd")
		(comment 1 "Grand Teton / footprints 2166-2167 of 8354")
	)
	(layers
		(0 "F.Cu" signal "TOP")
		(4 "In1.Cu" signal "GND")
		(6 "In2.Cu" signal "IN1")
		(8 "In3.Cu" signal "GND1")
		(10 "In4.Cu" signal "IN2")
		(12 "In5.Cu" signal "GND2")
		(14 "In6.Cu" signal "IN3")
		(16 "In7.Cu" signal "GND3")
		(18 "In8.Cu" signal "VCC")
		(20 "In9.Cu" signal "VCC1")
		(22 "In10.Cu" signal "GND4")
		(24 "In11.Cu" signal "IN4")
		(26 "In12.Cu" signal "GND5")
		(28 "In13.Cu" signal "IN5")
		(30 "In14.Cu" signal "GND6")
		(32 "In15.Cu" signal "IN6")
		(34 "In16.Cu" signal "GND7")
		(2 "B.Cu" signal "BOTTOM")
		(9 "F.Adhes" user "F.Adhesive")
		(11 "B.Adhes" user "B.Adhesive")
		(13 "F.Paste" user "Package Geometry/Pastemask Top")
		(15 "B.Paste" user "Package Geometry/Pastemask Bottom")
		(5 "F.SilkS" user "Ref Des/Silkscreen Top")
		(7 "B.SilkS" user "Ref Des/Silkscreen Bottom")
		(1 "F.Mask" user "Board Geometry/Soldermask Top")
		(3 "B.Mask" user "Board Geometry/Soldermask Bottom")
		(17 "Dwgs.User" user "User.Drawings")
		(19 "Cmts.User" user "User.Comments")
		(21 "Eco1.User" user "User.Eco1")
		(23 "Eco2.User" user "User.Eco2")
		(25 "Edge.Cuts" user "Board Geometry/Outline")
		(27 "Margin" user)
		(31 "F.CrtYd" user "Package Geometry/Place Bound Top")
		(29 "B.CrtYd" user "Package Geometry/Place Bound Bottom")
		(35 "F.Fab" user "Ref Des/Assembly Top")
		(33 "B.Fab" user "Ref Des/Assembly Bottom")
	)
	(footprint ""
		(layer "F.Cu")
		(at 351.410778 -158.474156 -90)
		(property "Reference" "PC151"
			(at 0 0 270)
			(layer "F.SilkS")
			(hide yes)
			(effects
				(font
					(size 1.27 1.27)
				)
			)
		)
		(property "Value" ""
			(at 0 0 270)
			(layer "F.Fab")
			(effects
				(font
					(size 1.27 1.27)
				)
			)
		)
		(duplicate_pad_numbers_are_jumpers no)
		(fp_line
			(start -0.7874 0.4064)
			(end -0.7874 -0.4064)
			(stroke
				(width 0.1524)
				(type default)
			)
			(layer "F.SilkS")
		)
		(fp_line
			(start -0.174244 0.4064)
			(end -0.7874 0.4064)
			(stroke
				(width 0.1524)
				(type default)
			)
			(layer "F.SilkS")
		)
		(fp_line
			(start 0.7874 0.4064)
			(end 0.359156 0.4064)
			(stroke
				(width 0.1524)
				(type default)
			)
			(layer "F.SilkS")
		)
		(fp_line
			(start -0.7874 -0.4064)
			(end 0.7874 -0.4064)
			(stroke
				(width 0.1524)
				(type default)
			)
			(layer "F.SilkS")
		)
		(fp_line
			(start 0.7874 -0.4064)
			(end 0.7874 0.4064)
			(stroke
				(width 0.1524)
				(type default)
			)
			(layer "F.SilkS")
		)
		(fp_line
			(start -0.67945 0.3048)
			(end -0.67945 -0.305054)
			(stroke
				(width 0.1)
				(type default)
			)
			(layer "F.Fab")
		)
		(fp_line
			(start -0.12065 0.3048)
			(end -0.67945 0.3048)
			(stroke
				(width 0.1)
				(type default)
			)
			(layer "F.Fab")
		)
		(fp_line
			(start 0.120396 0.3048)
			(end 0.120396 0.2794)
			(stroke
				(width 0.1)
				(type default)
			)
			(layer "F.Fab")
		)
		(fp_line
			(start 0.67945 0.3048)
			(end 0.120396 0.3048)
			(stroke
				(width 0.1)
				(type default)
			)
			(layer "F.Fab")
		)
		(fp_line
			(start -0.12065 0.2794)
			(end -0.12065 0.3048)
			(stroke
				(width 0.1)
				(type default)
			)
			(layer "F.Fab")
		)
		(fp_line
			(start 0.120396 0.2794)
			(end -0.12065 0.2794)
			(stroke
				(width 0.1)
				(type default)
			)
			(layer "F.Fab")
		)
		(fp_line
			(start -0.12065 -0.2794)
			(end 0.12065 -0.2794)
			(stroke
				(width 0.1)
				(type default)
			)
			(layer "F.Fab")
		)
		(fp_line
			(start 0.12065 -0.2794)
			(end 0.12065 -0.3048)
			(stroke
				(width 0.1)
				(type default)
			)
			(layer "F.Fab")
		)
		(fp_line
			(start 0.12065 -0.3048)
			(end 0.67945 -0.3048)
			(stroke
				(width 0.1)
				(type default)
			)
			(layer "F.Fab")
		)
		(fp_line
			(start 0.67945 -0.3048)
			(end 0.67945 0.3048)
			(stroke
				(width 0.1)
				(type default)
			)
			(layer "F.Fab")
		)
		(fp_line
			(start -0.67945 -0.305054)
			(end -0.12065 -0.305054)
			(stroke
				(width 0.1)
				(type default)
			)
			(layer "F.Fab")
		)
		(fp_line
			(start -0.12065 -0.305054)
			(end -0.12065 -0.2794)
			(stroke
				(width 0.1)
				(type default)
			)
			(layer "F.Fab")
		)
		(pad "1" smd circle
			(at -0.40005 0 270)
			(size 0 0)
			(layers "F.Cu" "F.Mask" "F.Paste")
			(net "PVDDCR_CPU0_P0_VCC6")
		)
		(pad "2" smd circle
			(at 0.40005 0 270)
			(size 0 0)
			(layers "F.Cu" "F.Mask" "F.Paste")
			(net "GND")
		)
	)
	(footprint ""
		(layer "F.Cu")
		(at 439.072782 -433.49926 90)
		(property "Reference" "R3472"
			(at 0 0 90)
			(layer "F.SilkS")
			(hide yes)
			(effects
				(font
					(size 1.27 1.27)
				)
			)
		)
		(property "Value" ""
			(at 0 0 90)
			(layer "F.Fab")
			(effects
				(font
					(size 1.27 1.27)
				)
			)
		)
		(duplicate_pad_numbers_are_jumpers no)
		(fp_line
			(start 0.7874 -0.4064)
			(end 0.7874 0.4064)
			(stroke
				(width 0.1524)
				(type default)
			)
			(layer "F.SilkS")
		)
		(fp_line
			(start -0.7874 -0.4064)
			(end 0.7874 -0.4064)
			(stroke
				(width 0.1524)
				(type default)
			)
			(layer "F.SilkS")
		)
		(fp_line
			(start 0.7874 0.4064)
			(end -0.7874 0.4064)
			(stroke
				(width 0.1524)
				(type default)
			)
			(layer "F.SilkS")
		)
		(fp_line
			(start -0.7874 0.4064)
			(end -0.7874 -0.4064)
			(stroke
				(width 0.1524)
				(type default)
			)
			(layer "F.SilkS")
		)
		(fp_line
			(start -0.12065 -0.305054)
			(end -0.12065 -0.2794)
			(stroke
				(width 0.1)
				(type default)
			)
			(layer "F.Fab")
		)
		(fp_line
			(start -0.67945 -0.305054)
			(end -0.12065 -0.305054)
			(stroke
				(width 0.1)
				(type default)
			)
			(layer "F.Fab")
		)
		(fp_line
			(start 0.67945 -0.3048)
			(end 0.67945 0.3048)
			(stroke
				(width 0.1)
				(type default)
			)
			(layer "F.Fab")
		)
		(fp_line
			(start 0.12065 -0.3048)
			(end 0.67945 -0.3048)
			(stroke
				(width 0.1)
				(type default)
			)
			(layer "F.Fab")
		)
		(fp_line
			(start 0.12065 -0.2794)
			(end 0.12065 -0.3048)
			(stroke
				(width 0.1)
				(type default)
			)
			(layer "F.Fab")
		)
		(fp_line
			(start -0.12065 -0.2794)
			(end 0.12065 -0.2794)
			(stroke
				(width 0.1)
				(type default)
			)
			(layer "F.Fab")
		)
		(fp_line
			(start 0.120396 0.2794)
			(end -0.12065 0.2794)
			(stroke
				(width 0.1)
				(type default)
			)
			(layer "F.Fab")
		)
		(fp_line
			(start -0.12065 0.2794)
			(end -0.12065 0.3048)
			(stroke
				(width 0.1)
				(type default)
			)
			(layer "F.Fab")
		)
		(fp_line
			(start 0.67945 0.3048)
			(end 0.120396 0.3048)
			(stroke
				(width 0.1)
				(type default)
			)
			(layer "F.Fab")
		)
		(fp_line
			(start 0.120396 0.3048)
			(end 0.120396 0.2794)
			(stroke
				(width 0.1)
				(type default)
			)
			(layer "F.Fab")
		)
		(fp_line
			(start -0.12065 0.3048)
			(end -0.67945 0.3048)
			(stroke
				(width 0.1)
				(type default)
			)
			(layer "F.Fab")
		)
		(fp_line
			(start -0.67945 0.3048)
			(end -0.67945 -0.305054)
			(stroke
				(width 0.1)
				(type default)
			)
			(layer "F.Fab")
		)
		(pad "1" smd circle
			(at -0.40005 0 90)
			(size 0 0)
			(layers "F.Cu" "F.Mask" "F.Paste")
			(net "GND")
		)
		(pad "2" smd circle
			(at 0.40005 0 90)
			(size 0 0)
			(layers "F.Cu" "F.Mask" "F.Paste")
			(net "GPU_WP_HW_CTRL_ISO_N")
		)
	)
)
